(kicad_pcb
	(version 20260206)
	(generator "pcbnew")
	(generator_version "10.0")
	(general
		(thickness 1.6)
		(legacy_teardrops no)
	)
	(paper "A4")
	(title_block
		(title "03242023_DA0F0TMBIJ0_F0T_Motherboard_J_brd_V01_OCP.brd")
		(comment 1 "Grand Teton / footprints 2904-2906 of 6105")
	)
	(layers
		(0 "F.Cu" signal "TOP")
		(4 "In1.Cu" signal "GND")
		(6 "In2.Cu" signal "IN1")
		(8 "In3.Cu" signal "GND1")
		(10 "In4.Cu" signal "IN2")
		(12 "In5.Cu" signal "GND2")
		(14 "In6.Cu" signal "IN3")
		(16 "In7.Cu" signal "GND3")
		(18 "In8.Cu" signal "VCC")
		(20 "In9.Cu" signal "VCC1")
		(22 "In10.Cu" signal "GND4")
		(24 "In11.Cu" signal "IN4")
		(26 "In12.Cu" signal "GND5")
		(28 "In13.Cu" signal "IN5")
		(30 "In14.Cu" signal "GND6")
		(32 "In15.Cu" signal "IN6")
		(34 "In16.Cu" signal "GND7")
		(2 "B.Cu" signal "BOTTOM")
		(9 "F.Adhes" user "F.Adhesive")
		(11 "B.Adhes" user "B.Adhesive")
		(13 "F.Paste" user "Package Geometry/Pastemask Top")
		(15 "B.Paste" user "Package Geometry/Pastemask Bottom")
		(5 "F.SilkS" user "Ref Des/Silkscreen Top")
		(7 "B.SilkS" user "Ref Des/Silkscreen Bottom")
		(1 "F.Mask" user "Board Geometry/Soldermask Top")
		(3 "B.Mask" user "Board Geometry/Soldermask Bottom")
		(17 "Dwgs.User" user "User.Drawings")
		(19 "Cmts.User" user "User.Comments")
		(21 "Eco1.User" user "User.Eco1")
		(23 "Eco2.User" user "User.Eco2")
		(25 "Edge.Cuts" user "Board Geometry/Outline")
		(27 "Margin" user)
		(31 "F.CrtYd" user "Package Geometry/Place Bound Top")
		(29 "B.CrtYd" user "Package Geometry/Place Bound Bottom")
		(35 "F.Fab" user "Ref Des/Assembly Top")
		(33 "B.Fab" user "Ref Des/Assembly Bottom")
	)
	(footprint ""
		(layer "F.Cu")
		(at 385.740148 -342.917018)
		(property "Reference" "PU6_P0_8"
			(at -3.30454 -6.38683 0)
			(unlocked yes)
			(layer "F.SilkS")
			(effects
				(font
					(size 0.7874 0.5842)
					(thickness 0.1524)
				)
				(justify left)
			)
		)
		(property "Value" ""
			(at 0 0 0)
			(layer "F.Fab")
			(effects
				(font
					(size 1.27 1.27)
				)
			)
		)
		(duplicate_pad_numbers_are_jumpers no)
		(fp_line
			(start -2.500122 -2.999994)
			(end -2.24409 -2.999994)
			(stroke
				(width 0.1524)
				(type default)
			)
			(layer "F.SilkS")
		)
		(fp_line
			(start -2.500122 -2.529078)
			(end -2.500122 -2.999994)
			(stroke
				(width 0.1524)
				(type default)
			)
			(layer "F.SilkS")
		)
		(fp_line
			(start -2.500122 0.6604)
			(end -2.500122 0.229108)
			(stroke
				(width 0.1524)
				(type default)
			)
			(layer "F.SilkS")
		)
		(fp_line
			(start -2.500122 2.999994)
			(end -2.500122 2.339594)
			(stroke
				(width 0.1524)
				(type default)
			)
			(layer "F.SilkS")
		)
		(fp_line
			(start -2.2987 2.999994)
			(end -2.500122 2.999994)
			(stroke
				(width 0.1524)
				(type default)
			)
			(layer "F.SilkS")
		)
		(fp_line
			(start 2.31394 -2.999994)
			(end 2.500122 -2.999994)
			(stroke
				(width 0.1524)
				(type default)
			)
			(layer "F.SilkS")
		)
		(fp_line
			(start 2.500122 -2.999994)
			(end 2.500122 -2.44348)
			(stroke
				(width 0.1524)
				(type default)
			)
			(layer "F.SilkS")
		)
		(fp_line
			(start 2.500122 2.339594)
			(end 2.500122 2.999994)
			(stroke
				(width 0.1524)
				(type default)
			)
			(layer "F.SilkS")
		)
		(fp_line
			(start 2.500122 2.999994)
			(end 2.2987 2.999994)
			(stroke
				(width 0.1524)
				(type default)
			)
			(layer "F.SilkS")
		)
		(fp_poly
			(pts
				(xy -2.21996 -3.632454) (xy -2.72796 -2.616454) (xy -3.23596 -3.632454)
			)
			(stroke
				(width 0)
				(type default)
			)
			(fill yes)
			(layer "F.SilkS")
		)
		(fp_line
			(start -2.500122 -2.999994)
			(end 2.500122 -2.999994)
			(stroke
				(width 0.1)
				(type default)
			)
			(layer "F.Fab")
		)
		(fp_line
			(start -2.500122 2.999994)
			(end -2.500122 -2.999994)
			(stroke
				(width 0.1)
				(type default)
			)
			(layer "F.Fab")
		)
		(fp_line
			(start 2.500122 -2.999994)
			(end 2.500122 2.999994)
			(stroke
				(width 0.1)
				(type default)
			)
			(layer "F.Fab")
		)
		(fp_line
			(start 2.500122 2.999994)
			(end -2.500122 2.999994)
			(stroke
				(width 0.1)
				(type default)
			)
			(layer "F.Fab")
		)
		(fp_poly
			(pts
				(xy -4.218432 -2.783078) (xy -4.218432 -1.767078) (xy -3.202432 -2.275078)
			)
			(stroke
				(width 0)
				(type default)
			)
			(fill yes)
			(layer "F.Fab")
		)
		(pad "1" smd rect
			(at -2.400046 -2.275078 90)
			(size 0.2286 0.6096)
			(layers "F.Cu" "F.Mask" "F.Paste")
			(net "PVCCIN_CPU0_VOS8")
		)
		(pad "2" smd rect
			(at -2.400046 -1.82499 90)
			(size 0.2286 0.6096)
			(layers "F.Cu" "F.Mask" "F.Paste")
			(net "GND")
		)
		(pad "3" smd rect
			(at -2.400046 -1.374902 90)
			(size 0.2286 0.6096)
			(layers "F.Cu" "F.Mask" "F.Paste")
			(net "PVCCIN_CPU0_VDD8")
		)
		(pad "4" smd rect
			(at -2.400046 -0.925068 90)
			(size 0.2286 0.6096)
			(layers "F.Cu" "F.Mask" "F.Paste")
			(net "PVCCIN_CPU0_PVCC")
		)
		(pad "5" smd rect
			(at -2.400046 -0.47498 90)
			(size 0.2286 0.6096)
			(layers "F.Cu" "F.Mask" "F.Paste")
			(net "GND")
		)
		(pad "6" smd rect
			(at -2.400046 -0.024892 90)
			(size 0.2286 0.6096)
			(layers "F.Cu" "F.Mask" "F.Paste")
			(net "Net_8565")
		)
		(pad "7_9-20_24" smd circle
			(at 0 1.150112 90)
			(size 0 0)
			(layers "F.Cu" "F.Mask" "F.Paste")
			(net "GND")
		)
		(pad "10_19" smd rect
			(at 0 2.899918 90)
			(size 0.6096 4.318)
			(layers "F.Cu" "F.Mask" "F.Paste")
			(net "SW_PVCCIN_CPU0_SW8")
		)
		(pad "25_29" smd rect
			(at 1.549908 -1.279906 270)
			(size 2.0574 2.3114)
			(layers "F.Cu" "F.Mask" "F.Paste")
			(net "SW_P12V_PVCCIN_CPU0_FLT")
		)
		(pad "30" smd rect
			(at 2.05994 -2.899918)
			(size 0.2286 0.6096)
			(layers "F.Cu" "F.Mask" "F.Paste")
			(net "SW_P12V_PVCCIN_CPU0_FLT")
		)
		(pad "31" smd rect
			(at 1.610106 -2.899918)
			(size 0.2286 0.6096)
			(layers "F.Cu" "F.Mask" "F.Paste")
			(net "Net_8566")
		)
		(pad "32" smd rect
			(at 1.160018 -2.899918)
			(size 0.2286 0.6096)
			(layers "F.Cu" "F.Mask" "F.Paste")
			(net "SW_PVCCIN_CPU0_BOOTR8")
		)
		(pad "33" smd rect
			(at 0.70993 -2.899918)
			(size 0.2286 0.6096)
			(layers "F.Cu" "F.Mask" "F.Paste")
			(net "SW_PVCCIN_CPU0_BOOT8")
		)
		(pad "34" smd rect
			(at 0.260096 -2.899918)
			(size 0.2286 0.6096)
			(layers "F.Cu" "F.Mask" "F.Paste")
			(net "PVCCIN_CPU0_PWM8")
		)
		(pad "35" smd rect
			(at -0.189992 -2.899918)
			(size 0.2286 0.6096)
			(layers "F.Cu" "F.Mask" "F.Paste")
			(net "PVCCIN_CPU0_VDD8")
		)
		(pad "36" smd rect
			(at -0.64008 -2.899918)
			(size 0.2286 0.6096)
			(layers "F.Cu" "F.Mask" "F.Paste")
			(net "PVCCIN_CPU0_ATSEN")
		)
		(pad "37" smd rect
			(at -1.089914 -2.899918)
			(size 0.2286 0.6096)
			(layers "F.Cu" "F.Mask" "F.Paste")
			(net "PVCCIN_CPU0_LSET8")
		)
		(pad "38" smd rect
			(at -1.540002 -2.899918)
			(size 0.2286 0.6096)
			(layers "F.Cu" "F.Mask" "F.Paste")
			(net "PVCCIN_CPU0_IMON8")
		)
		(pad "39" smd rect
			(at -1.99009 -2.899918)
			(size 0.2286 0.6096)
			(layers "F.Cu" "F.Mask" "F.Paste")
			(net "PVCCIN_CPU0_VREF")
		)
		(pad "40" smd rect
			(at -0.87503 -1.27508)
			(size 1.7526 1.9558)
			(layers "F.Cu" "F.Mask" "F.Paste")
			(net "GND")
		)
		(pad "41" smd rect
			(at -1.525016 0.249936 270)
			(size 0.3048 0.4572)
			(layers "F.Cu" "F.Mask" "F.Paste")
			(net "Net_8564")
		)
		(zone
			(layer "F.Cu")
			(hatch none 0.5)
			(connect_pads
				(clearance 0)
			)
			(min_thickness 0.25)
			(keepout
				(tracks not_allowed)
				(vias allowed)
				(pads allowed)
				(copperpour not_allowed)
				(footprints allowed)
			)
			(placement
				(enabled no)
				(sheetname "")
			)
			(fill
				(thermal_gap 0.5)
				(thermal_bridge_width 0.5)
				(island_removal_mode 0)
			)
			(polygon
				(pts
					(xy 383.240026 -339.917024) (xy 383.240026 -340.666324) (xy 388.24027 -340.666324) (xy 388.24027 -339.917024)
					(xy 387.949948 -339.917024) (xy 387.949948 -340.3727) (xy 383.530348 -340.3727) (xy 383.530348 -339.917024)
				)
			)
		)
		(zone
			(layer "F.Cu")
			(hatch none 0.5)
			(connect_pads
				(clearance 0)
			)
			(min_thickness 0.25)
			(keepout
				(tracks not_allowed)
				(vias allowed)
				(pads allowed)
				(copperpour not_allowed)
				(footprints allowed)
			)
			(placement
				(enabled no)
				(sheetname "")
			)
			(fill
				(thermal_gap 0.5)
				(thermal_bridge_width 0.5)
				(island_removal_mode 0)
			)
			(polygon
				(pts
					(xy 384.494532 -342.844628) (xy 384.72364 -342.844628) (xy 384.789426 -342.778842) (xy 384.789426 -342.167718)
					(xy 383.240026 -342.167718) (xy 383.240026 -342.62441) (xy 383.935732 -342.62441) (xy 383.935732 -342.463882)
					(xy 384.494532 -342.463882)
				)
			)
		)
	)
	(footprint ""
		(layer "F.Cu")
		(at 397.254476 -148.010118 90)
		(property "Reference" "PR520"
			(at 0 0 90)
			(layer "F.SilkS")
			(hide yes)
			(effects
				(font
					(size 1.27 1.27)
				)
			)
		)
		(property "Value" ""
			(at 0 0 90)
			(layer "F.Fab")
			(effects
				(font
					(size 1.27 1.27)
				)
			)
		)
		(duplicate_pad_numbers_are_jumpers no)
		(fp_line
			(start 0.7874 -0.4064)
			(end 0.7874 0.4064)
			(stroke
				(width 0.1524)
				(type default)
			)
			(layer "F.SilkS")
		)
		(fp_line
			(start -0.7874 -0.4064)
			(end 0.7874 -0.4064)
			(stroke
				(width 0.1524)
				(type default)
			)
			(layer "F.SilkS")
		)
		(fp_line
			(start 0.7874 0.4064)
			(end -0.7874 0.4064)
			(stroke
				(width 0.1524)
				(type default)
			)
			(layer "F.SilkS")
		)
		(fp_line
			(start -0.7874 0.4064)
			(end -0.7874 -0.4064)
			(stroke
				(width 0.1524)
				(type default)
			)
			(layer "F.SilkS")
		)
		(fp_line
			(start -0.12065 -0.305054)
			(end -0.12065 -0.2794)
			(stroke
				(width 0.1)
				(type default)
			)
			(layer "F.Fab")
		)
		(fp_line
			(start -0.67945 -0.305054)
			(end -0.12065 -0.305054)
			(stroke
				(width 0.1)
				(type default)
			)
			(layer "F.Fab")
		)
		(fp_line
			(start 0.67945 -0.3048)
			(end 0.67945 0.3048)
			(stroke
				(width 0.1)
				(type default)
			)
			(layer "F.Fab")
		)
		(fp_line
			(start 0.12065 -0.3048)
			(end 0.67945 -0.3048)
			(stroke
				(width 0.1)
				(type default)
			)
			(layer "F.Fab")
		)
		(fp_line
			(start 0.12065 -0.2794)
			(end 0.12065 -0.3048)
			(stroke
				(width 0.1)
				(type default)
			)
			(layer "F.Fab")
		)
		(fp_line
			(start -0.12065 -0.2794)
			(end 0.12065 -0.2794)
			(stroke
				(width 0.1)
				(type default)
			)
			(layer "F.Fab")
		)
		(fp_line
			(start 0.120396 0.2794)
			(end -0.12065 0.2794)
			(stroke
				(width 0.1)
				(type default)
			)
			(layer "F.Fab")
		)
		(fp_line
			(start -0.12065 0.2794)
			(end -0.12065 0.3048)
			(stroke
				(width 0.1)
				(type default)
			)
			(layer "F.Fab")
		)
		(fp_line
			(start 0.67945 0.3048)
			(end 0.120396 0.3048)
			(stroke
				(width 0.1)
				(type default)
			)
			(layer "F.Fab")
		)
		(fp_line
			(start 0.120396 0.3048)
			(end 0.120396 0.2794)
			(stroke
				(width 0.1)
				(type default)
			)
			(layer "F.Fab")
		)
		(fp_line
			(start -0.12065 0.3048)
			(end -0.67945 0.3048)
			(stroke
				(width 0.1)
				(type default)
			)
			(layer "F.Fab")
		)
		(fp_line
			(start -0.67945 0.3048)
			(end -0.67945 -0.305054)
			(stroke
				(width 0.1)
				(type default)
			)
			(layer "F.Fab")
		)
		(pad "1" smd circle
			(at -0.40005 0 90)
			(size 0 0)
			(layers "F.Cu" "F.Mask" "F.Paste")
			(net "VSENSE_PVCCFA_EHV_CPU0_DN")
		)
		(pad "2" smd circle
			(at 0.40005 0 90)
			(size 0 0)
			(layers "F.Cu" "F.Mask" "F.Paste")
			(net "GND")
		)
	)
	(footprint ""
		(layer "F.Cu")
		(at 118.542816 -249.320558 -90)
		(property "Reference" "C229"
			(at 0 0 270)
			(layer "F.SilkS")
			(hide yes)
			(effects
				(font
					(size 1.27 1.27)
				)
			)
		)
		(property "Value" ""
			(at 0 0 270)
			(layer "F.Fab")
			(effects
				(font
					(size 1.27 1.27)
				)
			)
		)
		(duplicate_pad_numbers_are_jumpers no)
		(fp_line
			(start -0.7874 0.4064)
			(end -0.7874 -0.4064)
			(stroke
				(width 0.1524)
				(type default)
			)
			(layer "F.SilkS")
		)
		(fp_line
			(start 0.7874 0.4064)
			(end -0.7874 0.4064)
			(stroke
				(width 0.1524)
				(type default)
			)
			(layer "F.SilkS")
		)
		(fp_line
			(start -0.7874 -0.4064)
			(end 0.7874 -0.4064)
			(stroke
				(width 0.1524)
				(type default)
			)
			(layer "F.SilkS")
		)
		(fp_line
			(start 0.7874 -0.4064)
			(end 0.7874 0.4064)
			(stroke
				(width 0.1524)
				(type default)
			)
			(layer "F.SilkS")
		)
		(fp_line
			(start -0.67945 0.3048)
			(end -0.67945 -0.305054)
			(stroke
				(width 0.1)
				(type default)
			)
			(layer "F.Fab")
		)
		(fp_line
			(start -0.12065 0.3048)
			(end -0.67945 0.3048)
			(stroke
				(width 0.1)
				(type default)
			)
			(layer "F.Fab")
		)
		(fp_line
			(start 0.120396 0.3048)
			(end 0.120396 0.2794)
			(stroke
				(width 0.1)
				(type default)
			)
			(layer "F.Fab")
		)
		(fp_line
			(start 0.67945 0.3048)
			(end 0.120396 0.3048)
			(stroke
				(width 0.1)
				(type default)
			)
			(layer "F.Fab")
		)
		(fp_line
			(start -0.12065 0.2794)
			(end -0.12065 0.3048)
			(stroke
				(width 0.1)
				(type default)
			)
			(layer "F.Fab")
		)
		(fp_line
			(start 0.120396 0.2794)
			(end -0.12065 0.2794)
			(stroke
				(width 0.1)
				(type default)
			)
			(layer "F.Fab")
		)
		(fp_line
			(start -0.12065 -0.2794)
			(end 0.12065 -0.2794)
			(stroke
				(width 0.1)
				(type default)
			)
			(layer "F.Fab")
		)
		(fp_line
			(start 0.12065 -0.2794)
			(end 0.12065 -0.3048)
			(stroke
				(width 0.1)
				(type default)
			)
			(layer "F.Fab")
		)
		(fp_line
			(start 0.12065 -0.3048)
			(end 0.67945 -0.3048)
			(stroke
				(width 0.1)
				(type default)
			)
			(layer "F.Fab")
		)
		(fp_line
			(start 0.67945 -0.3048)
			(end 0.67945 0.3048)
			(stroke
				(width 0.1)
				(type default)
			)
			(layer "F.Fab")
		)
		(fp_line
			(start -0.67945 -0.305054)
			(end -0.12065 -0.305054)
			(stroke
				(width 0.1)
				(type default)
			)
			(layer "F.Fab")
		)
		(fp_line
			(start -0.12065 -0.305054)
			(end -0.12065 -0.2794)
			(stroke
				(width 0.1)
				(type default)
			)
			(layer "F.Fab")
		)
		(pad "1" smd circle
			(at -0.40005 0 270)
			(size 0 0)
			(layers "F.Cu" "F.Mask" "F.Paste")
			(net "PVCCIN_CPU1")
		)
		(pad "2" smd circle
			(at 0.40005 0 270)
			(size 0 0)
			(layers "F.Cu" "F.Mask" "F.Paste")
			(net "GND")
		)
	)
)
